# T6G (Grand Teton) — schematic netlist excerpt (pin names and nets, part order shuffled) for the footprints in the layout excerpt that follows; sources: Cadence DE-HDL packaged netlist, KiCad conversion of 04192023_DAF0TMB3IC0_F0TG_MB_C_brd_V02_OCP.brd

PC114_6  Q_CAP  0.1UF 25V 10% X7R  pkg 0402  page 203 : A = SW_P12V_AUX_PVDDCR_CPU1_P0_FLT ; B = GND
H37  HOLE  EMPTY  pkg TH  page 230 : \1\ = GND
R9024  Q_RES  54.9K 1% CHIP  pkg 0402LF  page 267 : A = P3V3_AUX ; B = IRQ_HSC_FAULT_N

(kicad_pcb
	(version 20260206)
	(generator "pcbnew")
	(generator_version "10.0")
	(general
		(thickness 1.6)
		(legacy_teardrops no)
	)
	(paper "A4")
	(title_block
		(title "04192023_DAF0TMB3IC0_F0TG_MB_C_brd_V02_OCP.brd")
		(comment 1 "Grand Teton / footprints 908-910 of 8354")
	)
	(layers
		(0 "F.Cu" signal "TOP")
		(4 "In1.Cu" signal "GND")
		(6 "In2.Cu" signal "IN1")
		(8 "In3.Cu" signal "GND1")
		(10 "In4.Cu" signal "IN2")
		(12 "In5.Cu" signal "GND2")
		(14 "In6.Cu" signal "IN3")
		(16 "In7.Cu" signal "GND3")
		(18 "In8.Cu" signal "VCC")
		(20 "In9.Cu" signal "VCC1")
		(22 "In10.Cu" signal "GND4")
		(24 "In11.Cu" signal "IN4")
		(26 "In12.Cu" signal "GND5")
		(28 "In13.Cu" signal "IN5")
		(30 "In14.Cu" signal "GND6")
		(32 "In15.Cu" signal "IN6")
		(34 "In16.Cu" signal "GND7")
		(2 "B.Cu" signal "BOTTOM")
		(9 "F.Adhes" user "F.Adhesive")
		(11 "B.Adhes" user "B.Adhesive")
		(13 "F.Paste" user "Package Geometry/Pastemask Top")
		(15 "B.Paste" user "Package Geometry/Pastemask Bottom")
		(5 "F.SilkS" user "Ref Des/Silkscreen Top")
		(7 "B.SilkS" user "Ref Des/Silkscreen Bottom")
		(1 "F.Mask" user "Board Geometry/Soldermask Top")
		(3 "B.Mask" user "Board Geometry/Soldermask Bottom")
		(17 "Dwgs.User" user "User.Drawings")
		(19 "Cmts.User" user "User.Comments")
		(21 "Eco1.User" user "User.Eco1")
		(23 "Eco2.User" user "User.Eco2")
		(25 "Edge.Cuts" user "Board Geometry/Outline")
		(27 "Margin" user)
		(31 "F.CrtYd" user "Package Geometry/Place Bound Top")
		(29 "B.CrtYd" user "Package Geometry/Place Bound Bottom")
		(35 "F.Fab" user "Ref Des/Assembly Top")
		(33 "B.Fab" user "Ref Des/Assembly Bottom")
	)
	(footprint ""
		(layer "F.Cu")
		(at 164.719 -106.299 180)
		(property "Reference" "R9024"
			(at 0 0 180)
			(layer "F.SilkS")
			(hide yes)
			(effects
				(font
					(size 1.27 1.27)
				)
			)
		)
		(property "Value" ""
			(at 0 0 180)
			(layer "F.Fab")
			(effects
				(font
					(size 1.27 1.27)
				)
			)
		)
		(duplicate_pad_numbers_are_jumpers no)
		(fp_line
			(start 0.7874 0.4064)
			(end -0.7874 0.4064)
			(stroke
				(width 0.1524)
				(type default)
			)
			(layer "F.SilkS")
		)
		(fp_line
			(start 0.7874 -0.4064)
			(end 0.7874 0.4064)
			(stroke
				(width 0.1524)
				(type default)
			)
			(layer "F.SilkS")
		)
		(fp_line
			(start -0.7874 0.4064)
			(end -0.7874 -0.4064)
			(stroke
				(width 0.1524)
				(type default)
			)
			(layer "F.SilkS")
		)
		(fp_line
			(start -0.7874 -0.4064)
			(end 0.7874 -0.4064)
			(stroke
				(width 0.1524)
				(type default)
			)
			(layer "F.SilkS")
		)
		(fp_line
			(start 0.67945 0.3048)
			(end 0.120396 0.3048)
			(stroke
				(width 0.1)
				(type default)
			)
			(layer "F.Fab")
		)
		(fp_line
			(start 0.67945 -0.3048)
			(end 0.67945 0.3048)
			(stroke
				(width 0.1)
				(type default)
			)
			(layer "F.Fab")
		)
		(fp_line
			(start 0.12065 -0.2794)
			(end 0.12065 -0.3048)
			(stroke
				(width 0.1)
				(type default)
			)
			(layer "F.Fab")
		)
		(fp_line
			(start 0.12065 -0.3048)
			(end 0.67945 -0.3048)
			(stroke
				(width 0.1)
				(type default)
			)
			(layer "F.Fab")
		)
		(fp_line
			(start 0.120396 0.3048)
			(end 0.120396 0.2794)
			(stroke
				(width 0.1)
				(type default)
			)
			(layer "F.Fab")
		)
		(fp_line
			(start 0.120396 0.2794)
			(end -0.12065 0.2794)
			(stroke
				(width 0.1)
				(type default)
			)
			(layer "F.Fab")
		)
		(fp_line
			(start -0.12065 0.3048)
			(end -0.67945 0.3048)
			(stroke
				(width 0.1)
				(type default)
			)
			(layer "F.Fab")
		)
		(fp_line
			(start -0.12065 0.2794)
			(end -0.12065 0.3048)
			(stroke
				(width 0.1)
				(type default)
			)
			(layer "F.Fab")
		)
		(fp_line
			(start -0.12065 -0.2794)
			(end 0.12065 -0.2794)
			(stroke
				(width 0.1)
				(type default)
			)
			(layer "F.Fab")
		)
		(fp_line
			(start -0.12065 -0.305054)
			(end -0.12065 -0.2794)
			(stroke
				(width 0.1)
				(type default)
			)
			(layer "F.Fab")
		)
		(fp_line
			(start -0.67945 0.3048)
			(end -0.67945 -0.305054)
			(stroke
				(width 0.1)
				(type default)
			)
			(layer "F.Fab")
		)
		(fp_line
			(start -0.67945 -0.305054)
			(end -0.12065 -0.305054)
			(stroke
				(width 0.1)
				(type default)
			)
			(layer "F.Fab")
		)
		(pad "1" smd circle
			(at -0.40005 0 180)
			(size 0 0)
			(layers "F.Cu" "F.Mask" "F.Paste")
			(net "P3V3_AUX")
		)
		(pad "2" smd circle
			(at 0.40005 0 180)
			(size 0 0)
			(layers "F.Cu" "F.Mask" "F.Paste")
			(net "IRQ_HSC_FAULT_N")
		)
	)
	(footprint ""
		(layer "F.Cu")
		(at 317.452248 -344.814906)
		(property "Reference" "H37"
			(at 0.040132 -4.391914 0)
			(unlocked yes)
			(layer "F.SilkS")
			(effects
				(font
					(size 0.7874 0.5842)
					(thickness 0.1524)
				)
				(justify left)
			)
		)
		(property "Value" ""
			(at 0 0 0)
			(layer "F.Fab")
			(effects
				(font
					(size 1.27 1.27)
				)
			)
		)
		(duplicate_pad_numbers_are_jumpers no)
		(pad "1" thru_hole circle
			(at 0 0)
			(size 6.1976 6.1976)
			(drill 3.7338)
			(layers "*.Cu" "*.Mask")
			(remove_unused_layers no)
			(net "GND")
			(clearance -0.9779)
			(padstack
				(mode front_inner_back)
				(layer "Inner"
					(shape circle)
					(size 5.5372 5.5372)
					(clearance -0.6477)
				)
				(layer "B.Cu"
					(shape circle)
					(size 6.1976 6.1976)
					(clearance -0.9779)
				)
			)
		)
	)
	(footprint ""
		(layer "F.Cu")
		(at 347.575124 -344.35161)
		(property "Reference" "PC114_6"
			(at 0 0 0)
			(layer "F.SilkS")
			(hide yes)
			(effects
				(font
					(size 1.27 1.27)
				)
			)
		)
		(property "Value" ""
			(at 0 0 0)
			(layer "F.Fab")
			(effects
				(font
					(size 1.27 1.27)
				)
			)
		)
		(duplicate_pad_numbers_are_jumpers no)
		(fp_line
			(start -0.7874 -0.4064)
			(end 0.7874 -0.4064)
			(stroke
				(width 0.1524)
				(type default)
			)
			(layer "F.SilkS")
		)
		(fp_line
			(start -0.7874 0.4064)
			(end -0.7874 -0.4064)
			(stroke
				(width 0.1524)
				(type default)
			)
			(layer "F.SilkS")
		)
		(fp_line
			(start 0.7874 -0.4064)
			(end 0.7874 0.4064)
			(stroke
				(width 0.1524)
				(type default)
			)
			(layer "F.SilkS")
		)
		(fp_line
			(start 0.7874 0.4064)
			(end -0.7874 0.4064)
			(stroke
				(width 0.1524)
				(type default)
			)
			(layer "F.SilkS")
		)
		(fp_line
			(start -0.67945 -0.305054)
			(end -0.12065 -0.305054)
			(stroke
				(width 0.1)
				(type default)
			)
			(layer "F.Fab")
		)
		(fp_line
			(start -0.67945 0.3048)
			(end -0.67945 -0.305054)
			(stroke
				(width 0.1)
				(type default)
			)
			(layer "F.Fab")
		)
		(fp_line
			(start -0.12065 -0.305054)
			(end -0.12065 -0.2794)
			(stroke
				(width 0.1)
				(type default)
			)
			(layer "F.Fab")
		)
		(fp_line
			(start -0.12065 -0.2794)
			(end 0.12065 -0.2794)
			(stroke
				(width 0.1)
				(type default)
			)
			(layer "F.Fab")
		)
		(fp_line
			(start -0.12065 0.2794)
			(end -0.12065 0.3048)
			(stroke
				(width 0.1)
				(type default)
			)
			(layer "F.Fab")
		)
		(fp_line
			(start -0.12065 0.3048)
			(end -0.67945 0.3048)
			(stroke
				(width 0.1)
				(type default)
			)
			(layer "F.Fab")
		)
		(fp_line
			(start 0.120396 0.2794)
			(end -0.12065 0.2794)
			(stroke
				(width 0.1)
				(type default)
			)
			(layer "F.Fab")
		)
		(fp_line
			(start 0.120396 0.3048)
			(end 0.120396 0.2794)
			(stroke
				(width 0.1)
				(type default)
			)
			(layer "F.Fab")
		)
		(fp_line
			(start 0.12065 -0.3048)
			(end 0.67945 -0.3048)
			(stroke
				(width 0.1)
				(type default)
			)
			(layer "F.Fab")
		)
		(fp_line
			(start 0.12065 -0.2794)
			(end 0.12065 -0.3048)
			(stroke
				(width 0.1)
				(type default)
			)
			(layer "F.Fab")
		)
		(fp_line
			(start 0.67945 -0.3048)
			(end 0.67945 0.3048)
			(stroke
				(width 0.1)
				(type default)
			)
			(layer "F.Fab")
		)
		(fp_line
			(start 0.67945 0.3048)
			(end 0.120396 0.3048)
			(stroke
				(width 0.1)
				(type default)
			)
			(layer "F.Fab")
		)
		(pad "1" smd circle
			(at -0.40005 0)
			(size 0 0)
			(layers "F.Cu" "F.Mask" "F.Paste")
			(net "SW_P12V_AUX_PVDDCR_CPU1_P0_FLT")
		)
		(pad "2" smd circle
			(at 0.40005 0)
			(size 0 0)
			(layers "F.Cu" "F.Mask" "F.Paste")
			(net "GND")
		)
	)
)
